(kicad_pcb
	(version 20260206)
	(generator "pcbnew")
	(generator_version "10.0")
	(general
		(thickness 1.6)
		(legacy_teardrops no)
	)
	(paper "A4")
	(title_block
		(title "panther-plus-userver — 13130-1b_20150205.brd")
		(comment 1 "Honey Badger (Wiwynn) / footprints 396-403 of 1509")
	)
	(layers
		(0 "F.Cu" signal "TOP")
		(4 "In1.Cu" signal "L2")
		(6 "In2.Cu" signal "L3")
		(8 "In3.Cu" signal "L4")
		(10 "In4.Cu" signal "L5")
		(12 "In5.Cu" signal "L6")
		(14 "In6.Cu" signal "L7")
		(16 "In7.Cu" signal "L8")
		(18 "In8.Cu" signal "L9")
		(20 "In9.Cu" signal "L10")
		(22 "In10.Cu" signal "L11")
		(2 "B.Cu" signal "BOTTOM")
		(9 "F.Adhes" user "F.Adhesive")
		(11 "B.Adhes" user "B.Adhesive")
		(13 "F.Paste" user "Package Geometry/Pastemask Top")
		(15 "B.Paste" user "Package Geometry/Pastemask Bottom")
		(5 "F.SilkS" user "Ref Des/Silkscreen Top")
		(7 "B.SilkS" user "Ref Des/Silkscreen Bottom")
		(1 "F.Mask" user "Board Geometry/Soldermask Top")
		(3 "B.Mask" user "Board Geometry/Soldermask Bottom")
		(17 "Dwgs.User" user "User.Drawings")
		(19 "Cmts.User" user "User.Comments")
		(21 "Eco1.User" user "User.Eco1")
		(23 "Eco2.User" user "User.Eco2")
		(25 "Edge.Cuts" user "Board Geometry/Outline")
		(27 "Margin" user)
		(31 "F.CrtYd" user "Package Geometry/Place Bound Top")
		(29 "B.CrtYd" user "Package Geometry/Place Bound Bottom")
		(35 "F.Fab" user "Ref Des/Assembly Top")
		(33 "B.Fab" user "Ref Des/Assembly Bottom")
	)
	(footprint ""
		(layer "F.Cu")
		(at 12.1412 -52.7812 90)
		(property "Reference" "C57"
			(at 0 0 90)
			(layer "F.SilkS")
			(hide yes)
			(effects
				(font
					(size 1.27 1.27)
				)
			)
		)
		(property "Value" "SCD1U16V2KX-3GP"
			(at 1.1811 -2.7051 90)
			(unlocked yes)
			(layer "F.Fab")
			(hide yes)
			(effects
				(font
					(size 1.016 1.016)
					(thickness 0.1524)
				)
			)
		)
		(property "Device Type" "C402H22"
			(at 1.1811 -4.2291 90)
			(unlocked yes)
			(layer "F.Fab")
			(hide yes)
			(effects
				(font
					(size 1.016 1.016)
					(thickness 0.1524)
				)
			)
		)
		(duplicate_pad_numbers_are_jumpers no)
		(fp_rect
			(start -0.381 0.7366)
			(end 0.381 -0.7366)
			(stroke
				(width 0)
				(type default)
			)
			(fill no)
			(layer "F.CrtYd")
		)
		(fp_rect
			(start -0.381 0.7366)
			(end 0.381 -0.7366)
			(stroke
				(width 0)
				(type default)
			)
			(fill no)
			(layer "F.Fab")
		)
		(pad "1" smd custom
			(at 0 -0.4572 90)
			(size 0.1143 0.1143)
			(layers "F.Cu" "F.Mask" "F.Paste")
			(net "P2E_CPU_NGFF_C_RX_DP12")
			(options
				(clearance outline)
				(anchor circle)
			)
			(primitives
				(gr_poly
					(pts
						(arc
							(start -0.254 -0.1778)
							(mid -0.239121 -0.213721)
							(end -0.2032 -0.2286)
						)
						(arc
							(start 0.2032 -0.2286)
							(mid 0.239121 -0.213721)
							(end 0.254 -0.1778)
						)
						(arc
							(start 0.254 0.1778)
							(mid 0.239121 0.213721)
							(end 0.2032 0.2286)
						)
						(arc
							(start -0.2032 0.2286)
							(mid -0.239121 0.213721)
							(end -0.254 0.1778)
						)
					)
					(width 0)
					(fill yes)
				)
			)
		)
		(pad "2" smd custom
			(at 0 0.4572 90)
			(size 0.1143 0.1143)
			(layers "F.Cu" "F.Mask" "F.Paste")
			(net "P2E_CPU_NGFF_RX_DP12")
			(options
				(clearance outline)
				(anchor circle)
			)
			(primitives
				(gr_poly
					(pts
						(arc
							(start -0.254 -0.1778)
							(mid -0.239121 -0.213721)
							(end -0.2032 -0.2286)
						)
						(arc
							(start 0.2032 -0.2286)
							(mid 0.239121 -0.213721)
							(end 0.254 -0.1778)
						)
						(arc
							(start 0.254 0.1778)
							(mid 0.239121 0.213721)
							(end 0.2032 0.2286)
						)
						(arc
							(start -0.2032 0.2286)
							(mid -0.239121 0.213721)
							(end -0.254 0.1778)
						)
					)
					(width 0)
					(fill yes)
				)
			)
		)
	)
	(footprint ""
		(layer "F.Cu")
		(at 32.893 -18.415)
		(property "Reference" "R265"
			(at 0 0 0)
			(layer "F.SilkS")
			(hide yes)
			(effects
				(font
					(size 1.27 1.27)
				)
			)
		)
		(property "Value" "0R2J-2-GP"
			(at 0.064008 -3.993896 0)
			(unlocked yes)
			(layer "F.Fab")
			(hide yes)
			(effects
				(font
					(size 1.016 1.016)
					(thickness 0.1524)
				)
			)
		)
		(property "Device Type" "R402H16"
			(at 0.064008 -5.517896 0)
			(unlocked yes)
			(layer "F.Fab")
			(hide yes)
			(effects
				(font
					(size 1.016 1.016)
					(thickness 0.1524)
				)
			)
		)
		(duplicate_pad_numbers_are_jumpers no)
		(fp_rect
			(start -0.381 0.8382)
			(end 0.381 -0.8382)
			(stroke
				(width 0)
				(type default)
			)
			(fill no)
			(layer "F.CrtYd")
		)
		(fp_rect
			(start -0.381 0.8382)
			(end 0.381 -0.8382)
			(stroke
				(width 0)
				(type default)
			)
			(fill no)
			(layer "F.Fab")
		)
		(pad "1" smd custom
			(at 0 -0.4318)
			(size 0.127 0.127)
			(layers "F.Cu" "F.Mask" "F.Paste")
			(net "XDP_DFX_PORT_R_CLK0")
			(options
				(clearance outline)
				(anchor circle)
			)
			(primitives
				(gr_poly
					(pts
						(arc
							(start -0.2032 -0.2794)
							(mid -0.239121 -0.264521)
							(end -0.254 -0.2286)
						)
						(arc
							(start -0.254 0.2286)
							(mid -0.239121 0.264521)
							(end -0.2032 0.2794)
						)
						(arc
							(start 0.2032 0.2794)
							(mid 0.239121 0.264521)
							(end 0.254 0.2286)
						)
						(arc
							(start 0.254 -0.2286)
							(mid 0.239121 -0.264521)
							(end 0.2032 -0.2794)
						)
					)
					(width 0)
					(fill yes)
				)
			)
		)
		(pad "2" smd custom
			(at 0 0.4318)
			(size 0.127 0.127)
			(layers "F.Cu" "F.Mask" "F.Paste")
			(net "XDP_DFX_PORT_CLK0")
			(options
				(clearance outline)
				(anchor circle)
			)
			(primitives
				(gr_poly
					(pts
						(arc
							(start -0.2032 -0.2794)
							(mid -0.239121 -0.264521)
							(end -0.254 -0.2286)
						)
						(arc
							(start -0.254 0.2286)
							(mid -0.239121 0.264521)
							(end -0.2032 0.2794)
						)
						(arc
							(start 0.2032 0.2794)
							(mid 0.239121 0.264521)
							(end 0.254 0.2286)
						)
						(arc
							(start 0.254 -0.2286)
							(mid 0.239121 -0.264521)
							(end 0.2032 -0.2794)
						)
					)
					(width 0)
					(fill yes)
				)
			)
		)
	)
	(footprint ""
		(layer "F.Cu")
		(at 44.323 -18.415 -90)
		(property "Reference" "R363"
			(at 0 0 270)
			(layer "F.SilkS")
			(hide yes)
			(effects
				(font
					(size 1.27 1.27)
				)
			)
		)
		(property "Value" "4K7R2F-GP"
			(at 0.064008 -3.993896 270)
			(unlocked yes)
			(layer "F.Fab")
			(hide yes)
			(effects
				(font
					(size 1.016 1.016)
					(thickness 0.1524)
				)
			)
		)
		(property "Device Type" "R402H16"
			(at 0.064008 -5.517896 270)
			(unlocked yes)
			(layer "F.Fab")
			(hide yes)
			(effects
				(font
					(size 1.016 1.016)
					(thickness 0.1524)
				)
			)
		)
		(duplicate_pad_numbers_are_jumpers no)
		(fp_rect
			(start -0.381 0.8382)
			(end 0.381 -0.8382)
			(stroke
				(width 0)
				(type default)
			)
			(fill no)
			(layer "F.CrtYd")
		)
		(fp_rect
			(start -0.381 0.8382)
			(end 0.381 -0.8382)
			(stroke
				(width 0)
				(type default)
			)
			(fill no)
			(layer "F.Fab")
		)
		(pad "1" smd custom
			(at 0 -0.4318 270)
			(size 0.127 0.127)
			(layers "F.Cu" "F.Mask" "F.Paste")
			(net "CLKBUFF_OE2#")
			(options
				(clearance outline)
				(anchor circle)
			)
			(primitives
				(gr_poly
					(pts
						(arc
							(start -0.2032 -0.2794)
							(mid -0.239121 -0.264521)
							(end -0.254 -0.2286)
						)
						(arc
							(start -0.254 0.2286)
							(mid -0.239121 0.264521)
							(end -0.2032 0.2794)
						)
						(arc
							(start 0.2032 0.2794)
							(mid 0.239121 0.264521)
							(end 0.254 0.2286)
						)
						(arc
							(start 0.254 -0.2286)
							(mid 0.239121 -0.264521)
							(end 0.2032 -0.2794)
						)
					)
					(width 0)
					(fill yes)
				)
			)
		)
		(pad "2" smd custom
			(at 0 0.4318 270)
			(size 0.127 0.127)
			(layers "F.Cu" "F.Mask" "F.Paste")
			(net "GND")
			(options
				(clearance outline)
				(anchor circle)
			)
			(primitives
				(gr_poly
					(pts
						(arc
							(start -0.2032 -0.2794)
							(mid -0.239121 -0.264521)
							(end -0.254 -0.2286)
						)
						(arc
							(start -0.254 0.2286)
							(mid -0.239121 0.264521)
							(end -0.2032 0.2794)
						)
						(arc
							(start 0.2032 0.2794)
							(mid 0.239121 0.264521)
							(end 0.254 0.2286)
						)
						(arc
							(start 0.254 -0.2286)
							(mid 0.239121 -0.264521)
							(end 0.2032 -0.2794)
						)
					)
					(width 0)
					(fill yes)
				)
			)
		)
	)
	(footprint ""
		(layer "F.Cu")
		(at 46.355 -22.733)
		(property "Reference" "C207"
			(at 0 0 0)
			(layer "F.SilkS")
			(hide yes)
			(effects
				(font
					(size 1.27 1.27)
				)
			)
		)
		(property "Value" "SCD1U10V2KX-5GP"
			(at 1.1811 -2.7051 0)
			(unlocked yes)
			(layer "F.Fab")
			(hide yes)
			(effects
				(font
					(size 1.016 1.016)
					(thickness 0.1524)
				)
			)
		)
		(property "Device Type" "C402H22"
			(at 1.1811 -4.2291 0)
			(unlocked yes)
			(layer "F.Fab")
			(hide yes)
			(effects
				(font
					(size 1.016 1.016)
					(thickness 0.1524)
				)
			)
		)
		(duplicate_pad_numbers_are_jumpers no)
		(fp_rect
			(start -0.381 0.7366)
			(end 0.381 -0.7366)
			(stroke
				(width 0)
				(type default)
			)
			(fill no)
			(layer "F.CrtYd")
		)
		(fp_rect
			(start -0.381 0.7366)
			(end 0.381 -0.7366)
			(stroke
				(width 0)
				(type default)
			)
			(fill no)
			(layer "F.Fab")
		)
		(pad "1" smd custom
			(at 0 -0.4572)
			(size 0.1143 0.1143)
			(layers "F.Cu" "F.Mask" "F.Paste")
			(net "P3V3_VDD_CLKBUFF")
			(options
				(clearance outline)
				(anchor circle)
			)
			(primitives
				(gr_poly
					(pts
						(arc
							(start -0.254 -0.1778)
							(mid -0.239121 -0.213721)
							(end -0.2032 -0.2286)
						)
						(arc
							(start 0.2032 -0.2286)
							(mid 0.239121 -0.213721)
							(end 0.254 -0.1778)
						)
						(arc
							(start 0.254 0.1778)
							(mid 0.239121 0.213721)
							(end 0.2032 0.2286)
						)
						(arc
							(start -0.2032 0.2286)
							(mid -0.239121 0.213721)
							(end -0.254 0.1778)
						)
					)
					(width 0)
					(fill yes)
				)
			)
		)
		(pad "2" smd custom
			(at 0 0.4572)
			(size 0.1143 0.1143)
			(layers "F.Cu" "F.Mask" "F.Paste")
			(net "GND")
			(options
				(clearance outline)
				(anchor circle)
			)
			(primitives
				(gr_poly
					(pts
						(arc
							(start -0.254 -0.1778)
							(mid -0.239121 -0.213721)
							(end -0.2032 -0.2286)
						)
						(arc
							(start 0.2032 -0.2286)
							(mid 0.239121 -0.213721)
							(end 0.254 -0.1778)
						)
						(arc
							(start 0.254 0.1778)
							(mid 0.239121 0.213721)
							(end 0.2032 0.2286)
						)
						(arc
							(start -0.2032 0.2286)
							(mid -0.239121 0.213721)
							(end -0.254 0.1778)
						)
					)
					(width 0)
					(fill yes)
				)
			)
		)
	)
	(footprint ""
		(layer "F.Cu")
		(at 9.4488 -47.498 -90)
		(property "Reference" "R12"
			(at 0 0 270)
			(layer "F.SilkS")
			(hide yes)
			(effects
				(font
					(size 1.27 1.27)
				)
			)
		)
		(property "Value" "4K7R2F-GP"
			(at 0.064008 -3.993896 270)
			(unlocked yes)
			(layer "F.Fab")
			(hide yes)
			(effects
				(font
					(size 1.016 1.016)
					(thickness 0.1524)
				)
			)
		)
		(property "Device Type" "R402H16"
			(at 0.064008 -5.517896 270)
			(unlocked yes)
			(layer "F.Fab")
			(hide yes)
			(effects
				(font
					(size 1.016 1.016)
					(thickness 0.1524)
				)
			)
		)
		(duplicate_pad_numbers_are_jumpers no)
		(fp_rect
			(start -0.381 0.8382)
			(end 0.381 -0.8382)
			(stroke
				(width 0)
				(type default)
			)
			(fill no)
			(layer "F.CrtYd")
		)
		(fp_rect
			(start -0.381 0.8382)
			(end 0.381 -0.8382)
			(stroke
				(width 0)
				(type default)
			)
			(fill no)
			(layer "F.Fab")
		)
		(pad "1" smd custom
			(at 0 -0.4318 270)
			(size 0.127 0.127)
			(layers "F.Cu" "F.Mask" "F.Paste")
			(net "P3V3_STBY")
			(options
				(clearance outline)
				(anchor circle)
			)
			(primitives
				(gr_poly
					(pts
						(arc
							(start -0.2032 -0.2794)
							(mid -0.239121 -0.264521)
							(end -0.254 -0.2286)
						)
						(arc
							(start -0.254 0.2286)
							(mid -0.239121 0.264521)
							(end -0.2032 0.2794)
						)
						(arc
							(start 0.2032 0.2794)
							(mid 0.239121 0.264521)
							(end 0.254 0.2286)
						)
						(arc
							(start 0.254 -0.2286)
							(mid 0.239121 -0.264521)
							(end 0.2032 -0.2794)
						)
					)
					(width 0)
					(fill yes)
				)
			)
		)
		(pad "2" smd custom
			(at 0 0.4318 270)
			(size 0.127 0.127)
			(layers "F.Cu" "F.Mask" "F.Paste")
			(net "TEMP_1_A2")
			(options
				(clearance outline)
				(anchor circle)
			)
			(primitives
				(gr_poly
					(pts
						(arc
							(start -0.2032 -0.2794)
							(mid -0.239121 -0.264521)
							(end -0.254 -0.2286)
						)
						(arc
							(start -0.254 0.2286)
							(mid -0.239121 0.264521)
							(end -0.2032 0.2794)
						)
						(arc
							(start 0.2032 0.2794)
							(mid 0.239121 0.264521)
							(end 0.254 0.2286)
						)
						(arc
							(start 0.254 -0.2286)
							(mid 0.239121 -0.264521)
							(end 0.2032 -0.2794)
						)
					)
					(width 0)
					(fill yes)
				)
			)
		)
	)
	(footprint ""
		(layer "F.Cu")
		(at 31.75 -15.748)
		(property "Reference" "R417"
			(at 0 0 0)
			(layer "F.SilkS")
			(hide yes)
			(effects
				(font
					(size 1.27 1.27)
				)
			)
		)
		(property "Value" "0R2J-2-GP"
			(at 1.7907 -1.1176 0)
			(unlocked yes)
			(layer "F.Fab")
			(hide yes)
			(effects
				(font
					(size 1.016 1.016)
					(thickness 0.1524)
				)
			)
		)
		(property "Device Type" "R402H16"
			(at 1.7907 -2.6416 0)
			(unlocked yes)
			(layer "F.Fab")
			(hide yes)
			(effects
				(font
					(size 1.016 1.016)
					(thickness 0.1524)
				)
			)
		)
		(duplicate_pad_numbers_are_jumpers no)
		(fp_rect
			(start -0.381 0.8382)
			(end 0.381 -0.8382)
			(stroke
				(width 0)
				(type default)
			)
			(fill no)
			(layer "F.CrtYd")
		)
		(fp_rect
			(start -0.381 0.8382)
			(end 0.381 -0.8382)
			(stroke
				(width 0)
				(type default)
			)
			(fill no)
			(layer "F.Fab")
		)
		(pad "1" smd custom
			(at 0 -0.4318)
			(size 0.127 0.127)
			(layers "F.Cu" "F.Mask" "F.Paste")
			(net "CPU_RSMRST#")
			(options
				(clearance outline)
				(anchor circle)
			)
			(primitives
				(gr_poly
					(pts
						(arc
							(start -0.2032 -0.2794)
							(mid -0.239121 -0.264521)
							(end -0.254 -0.2286)
						)
						(arc
							(start -0.254 0.2286)
							(mid -0.239121 0.264521)
							(end -0.2032 0.2794)
						)
						(arc
							(start 0.2032 0.2794)
							(mid 0.239121 0.264521)
							(end 0.254 0.2286)
						)
						(arc
							(start 0.254 -0.2286)
							(mid 0.239121 -0.264521)
							(end 0.2032 -0.2794)
						)
					)
					(width 0)
					(fill yes)
				)
			)
		)
		(pad "2" smd custom
			(at 0 0.4318)
			(size 0.127 0.127)
			(layers "F.Cu" "F.Mask" "F.Paste")
			(net "PICE_GF_I2C_SW_EN")
			(options
				(clearance outline)
				(anchor circle)
			)
			(primitives
				(gr_poly
					(pts
						(arc
							(start -0.2032 -0.2794)
							(mid -0.239121 -0.264521)
							(end -0.254 -0.2286)
						)
						(arc
							(start -0.254 0.2286)
							(mid -0.239121 0.264521)
							(end -0.2032 0.2794)
						)
						(arc
							(start 0.2032 0.2794)
							(mid 0.239121 0.264521)
							(end 0.254 0.2286)
						)
						(arc
							(start 0.254 -0.2286)
							(mid 0.239121 -0.264521)
							(end 0.2032 -0.2794)
						)
					)
					(width 0)
					(fill yes)
				)
			)
		)
	)
	(footprint ""
		(layer "F.Cu")
		(at 101.0666 -68.8594)
		(property "Reference" "PR8"
			(at 0 0 0)
			(layer "F.SilkS")
			(hide yes)
			(effects
				(font
					(size 1.27 1.27)
				)
			)
		)
		(property "Value" "0R2J-2-GP"
			(at 0.064008 -3.993896 0)
			(unlocked yes)
			(layer "F.Fab")
			(hide yes)
			(effects
				(font
					(size 1.016 1.016)
					(thickness 0.1524)
				)
			)
		)
		(property "Device Type" "R402H16"
			(at 0.064008 -5.517896 0)
			(unlocked yes)
			(layer "F.Fab")
			(hide yes)
			(effects
				(font
					(size 1.016 1.016)
					(thickness 0.1524)
				)
			)
		)
		(duplicate_pad_numbers_are_jumpers no)
		(fp_rect
			(start -0.381 0.8382)
			(end 0.381 -0.8382)
			(stroke
				(width 0)
				(type default)
			)
			(fill no)
			(layer "F.CrtYd")
		)
		(fp_rect
			(start -0.381 0.8382)
			(end 0.381 -0.8382)
			(stroke
				(width 0)
				(type default)
			)
			(fill no)
			(layer "F.Fab")
		)
		(pad "1" smd custom
			(at 0 -0.4318)
			(size 0.127 0.127)
			(layers "F.Cu" "F.Mask" "F.Paste")
			(net "PWRGD_PVCCP_VNN_PG")
			(options
				(clearance outline)
				(anchor circle)
			)
			(primitives
				(gr_poly
					(pts
						(arc
							(start -0.2032 -0.2794)
							(mid -0.239121 -0.264521)
							(end -0.254 -0.2286)
						)
						(arc
							(start -0.254 0.2286)
							(mid -0.239121 0.264521)
							(end -0.2032 0.2794)
						)
						(arc
							(start 0.2032 0.2794)
							(mid 0.239121 0.264521)
							(end 0.254 0.2286)
						)
						(arc
							(start 0.254 -0.2286)
							(mid 0.239121 -0.264521)
							(end 0.2032 -0.2794)
						)
					)
					(width 0)
					(fill yes)
				)
			)
		)
		(pad "2" smd custom
			(at 0 0.4318)
			(size 0.127 0.127)
			(layers "F.Cu" "F.Mask" "F.Paste")
			(net "VR_P1V1_EN")
			(options
				(clearance outline)
				(anchor circle)
			)
			(primitives
				(gr_poly
					(pts
						(arc
							(start -0.2032 -0.2794)
							(mid -0.239121 -0.264521)
							(end -0.254 -0.2286)
						)
						(arc
							(start -0.254 0.2286)
							(mid -0.239121 0.264521)
							(end -0.2032 0.2794)
						)
						(arc
							(start 0.2032 0.2794)
							(mid 0.239121 0.264521)
							(end 0.254 0.2286)
						)
						(arc
							(start 0.254 -0.2286)
							(mid 0.239121 -0.264521)
							(end 0.2032 -0.2794)
						)
					)
					(width 0)
					(fill yes)
				)
			)
		)
	)
	(footprint ""
		(layer "F.Cu")
		(at 22.733 -65.1764 180)
		(property "Reference" "PR29"
			(at 0 0 180)
			(layer "F.SilkS")
			(hide yes)
			(effects
				(font
					(size 1.27 1.27)
				)
			)
		)
		(property "Value" "100R2F-L1-GP-U"
			(at 1.7907 -1.1176 180)
			(unlocked yes)
			(layer "F.Fab")
			(hide yes)
			(effects
				(font
					(size 1.016 1.016)
					(thickness 0.1524)
				)
			)
		)
		(property "Device Type" "R402H14"
			(at 1.7907 -2.6416 180)
			(unlocked yes)
			(layer "F.Fab")
			(hide yes)
			(effects
				(font
					(size 1.016 1.016)
					(thickness 0.1524)
				)
			)
		)
		(duplicate_pad_numbers_are_jumpers no)
		(fp_rect
			(start -0.381 0.8382)
			(end 0.381 -0.8382)
			(stroke
				(width 0)
				(type default)
			)
			(fill no)
			(layer "F.CrtYd")
		)
		(fp_rect
			(start -0.381 0.8382)
			(end 0.381 -0.8382)
			(stroke
				(width 0)
				(type default)
			)
			(fill no)
			(layer "F.Fab")
		)
		(pad "1" smd custom
			(at 0 -0.4318 180)
			(size 0.127 0.127)
			(layers "F.Cu" "F.Mask" "F.Paste")
			(net "VR_PVNN_ISUMN_R")
			(options
				(clearance outline)
				(anchor circle)
			)
			(primitives
				(gr_poly
					(pts
						(arc
							(start -0.2032 -0.2794)
							(mid -0.239121 -0.264521)
							(end -0.254 -0.2286)
						)
						(arc
							(start -0.254 0.2286)
							(mid -0.239121 0.264521)
							(end -0.2032 0.2794)
						)
						(arc
							(start 0.2032 0.2794)
							(mid 0.239121 0.264521)
							(end 0.254 0.2286)
						)
						(arc
							(start 0.254 -0.2286)
							(mid 0.239121 -0.264521)
							(end 0.2032 -0.2794)
						)
					)
					(width 0)
					(fill yes)
				)
			)
		)
		(pad "2" smd custom
			(at 0 0.4318 180)
			(size 0.127 0.127)
			(layers "F.Cu" "F.Mask" "F.Paste")
			(net "VR_PVNN_ISUMN_RC")
			(options
				(clearance outline)
				(anchor circle)
			)
			(primitives
				(gr_poly
					(pts
						(arc
							(start -0.2032 -0.2794)
							(mid -0.239121 -0.264521)
							(end -0.254 -0.2286)
						)
						(arc
							(start -0.254 0.2286)
							(mid -0.239121 0.264521)
							(end -0.2032 0.2794)
						)
						(arc
							(start 0.2032 0.2794)
							(mid 0.239121 0.264521)
							(end 0.254 0.2286)
						)
						(arc
							(start 0.254 -0.2286)
							(mid 0.239121 -0.264521)
							(end 0.2032 -0.2794)
						)
					)
					(width 0)
					(fill yes)
				)
			)
		)
	)
)
